FILE_TYPE = CONNECTIVITY;
{Allegro Design Entry HDL 17.4-2019 S026 (4007227) 1/17/2022}
"PAGE_NUMBER" = 325;
0"NC";
1"AGND_HSC\g";
2"HSC_VDD\g";
3"AGND_HSC\g";
4"AGND_HSC\g";
5"AGND_HSC\g";
6"HSC_VDD\g";
7"HSC_CS_4";
8"AGND_HSC\g";
9"AGND_HSC\g";
10"HSC_IMON";
11"HSC_CS_3";
12"HSC_SCREF";
13"AGND_HSC\g";
14"HSC_VDD_R_3";
15"HSC_SCREF_4";
16"HSC_SCREF";
17"HSC_FLT_TYPE";
18"HSC_NC1_3";
19"HSC_SCREF_3";
20"HSC_OCREF";
21"HSC_ON";
22"HSC_MODE_3";
23"HSC_FLT_TYPE_3";
24"HSC_D_OC_3";
25"HSC_D_OC_R";
26"HSC_FLT_TYPE";
27"HSC_FAULT";
28"HSC_VTEMP";
29"HSC_SS";
30"HSC_ON";
31"HSC_IMON";
32"HSC_OCREF";
33"HSC_MODE_4";
34"HSC_VDD_R_4";
35"P12V_PSU\g";
36"P12V_PSU\g";
37"P12V_AUX\g";
38"P12V_AUX\g";
39"AGND_HSC\g";
40"HSC_D_OC_R";
41"HSC_D_OC_4";
42"HSC_SS";
43"HSC_VTEMP";
44"HSC_FAULT";
45"HSC_NC1_4";
46"HSC_FLT_TYPE_4";
%"UNIVERSAL_GND"
"1","(-2700,-2250)","0","pure_quanta_power","I1";
;
HDL_POWER"AGND_HSC"
CDS_LIB"pure_quanta_power";
"A"8;
%"Q_RES"
"1","(-1900,-1125)","0","pure_quanta","I11";
;
LOCATION"PR3984"
$SEC"1"
CDS_SEC"1"
ROOM"HSC BOM1"
VALUE"120K"
TOLERANCE"1%"
PACK_TYPE"0402LF"
MATERIAL"CHIP"
WATTAGE"1/16W"
CDS_LIB"pure_quanta"
PART_NUMBER"CS41202FB05";
"B"
$PN"2"33;
"A"
$PN"1"39;
%"Q_CAP"
"1","(-1975,-1950)","0","pure_quanta","I12";
;
LOCATION"PC2349"
$SEC"1"
CDS_SEC"1"
PACK_TYPE"0402"
VALUE"1NF"
MATERIAL"EMPTY"
VOLTAGE"50V"
ROOM"HSC BOM1"
CDS_LIB"pure_quanta"
TOLERANCE"10%"
PART_NUMBER"CH21006KB16";
"B"
$PN"2"8;
"A"
$PN"1"32;
%"Q_RES"
"2","(-1475,-1950)","0","pure_quanta","I13";
;
LOCATION"PR3987"
$SEC"1"
CDS_SEC"1"
MATERIAL"CHIP"
VALUE"2K"
TOLERANCE"0.1%"
ROOM"HSC BOM1"
PACK_TYPE"0402LF"
WATTAGE"1/16W"
CDS_LIB"pure_quanta"
PART_NUMBER"CS22002BB07";
"A"
$PN"1"7;
"B"
$PN"2"8;
%"Q_RES"
"2","(-950,-1950)","0","pure_quanta","I14";
;
LOCATION"PR3991"
$SEC"1"
CDS_SEC"1"
WATTAGE"1/16W"
MATERIAL"CHIP"
PACK_TYPE"0402LF"
VALUE"2K"
TOLERANCE"0.1%"
ROOM"HSC BOM1"
CDS_LIB"pure_quanta"
PART_NUMBER"CS22002BB07";
"A"
$PN"1"31;
"B"
$PN"2"8;
%"Q_RES"
"1","(-1300,-1300)","0","pure_quanta","I16";
;
LOCATION"PR3989"
$SEC"1"
CDS_SEC"1"
ROOM"HSC BOM1"
WATTAGE"1/16W"
TOLERANCE"5%"
VALUE"0"
MATERIAL"CHIP"
PACK_TYPE"0402LF"
CDS_LIB"pure_quanta"
PART_NUMBER"CS00002JB13";
"B"
$PN"2"15;
"A"
$PN"1"16;
%"MP5991GLUZ"
"1","(25,-1200)","0","pure_quanta","I17";
;
LOCATION"PU297"
SEC"1"
MATERIAL"IC"
PART_TYPE"SMLF"
ROOM"HSC BOM1"
VALUE"MP5991GLU-Z"
SEC_TYPE""
CDS_LIB"pure_quanta"
CDS_LMAN_SYM_OUTLINE"-325,775,325,-775"
NEEDS_NO_SIZE"TRUE"
PART_NUMBER"AL005991A00";
"NC1"
$PN"7"45;
"FLT_TYPE"
$PN"6"46;
"SCREF_OCWREF"
$PN"17"15;
"MODE"
$PN"8"33;
"VOUT10"
$PN"32"37;
"VOUT9"
$PN"31"37;
"VOUT8"
$PN"30"37;
"VOUT7"
$PN"29"37;
"VOUT6"
$PN"28"37;
"VOUT5"
$PN"27"37;
"VIN9"
$PN"33"35;
"VIN8"
$PN"16"35;
"VIN7"
$PN"15"35;
"VIN6"
$PN"14"35;
"D_OC"
$PN"3"41;
"VOUT4"
$PN"26"37;
"VOUT3"
$PN"25"37;
"VOUT2"
$PN"2"37;
"VOUT1"
$PN"1"37;
"VTEMP"
$PN"18"43;
"GOK"
$PN"5"44;
"SS"
$PN"19"42;
"GND"
$PN"20"8;
"VDD33"
$PN"21"34;
"IMON"
$PN"22"31;
"CS"
$PN"23"7;
"OCREF"
$PN"24"32;
"ON"
$PN"4"30;
"VIN5"
$PN"13"35;
"VIN4"
$PN"12"35;
"VIN3"
$PN"11"35;
"VIN2"
$PN"10"35;
"VIN1"
$PN"9"35;
%"UNIVERSAL_POWER"
"1","(-950,-325)","0","pure_quanta_power","I18";
;
HDL_POWER"P12V_PSU"
BOM_COST"MIO_VRD_SB"
CDS_LIB"pure_quanta_power";
"A"35;
%"UNIVERSAL_GND"
"1","(-3600,1175)","0","pure_quanta_power","I19";
;
HDL_POWER"AGND_HSC"
CDS_LIB"pure_quanta_power";
"A"1;
%"Q_CAP"
"1","(-2700,-1950)","0","pure_quanta","I2";
;
LOCATION"PC2225"
$SEC"1"
CDS_SEC"1"
PACK_TYPE"0402"
MATERIAL"EMPTY"
VALUE"220PF"
VOLTAGE"50V"
ROOM"HSC BOM1"
TOLERANCE"10%"
CDS_LIB"pure_quanta"
PART_NUMBER"TMP_QCH12206KB14";
"B"
$PN"2"8;
"A"
$PN"1"30;
%"Q_CAP"
"1","(-3600,1475)","0","pure_quanta","I20";
;
LOCATION"PC3272"
$SEC"1"
CDS_SEC"1"
VOLTAGE"25V"
MATERIAL"X6S"
ROOM"HSC BOM1"
PACK_TYPE"C0402"
VALUE"1UF"
CDS_LIB"pure_quanta"
TOLERANCE"10%"
PART_NUMBER"CH5104KEB02";
"B"
$PN"2"1;
"A"
$PN"1"14;
%"Q_RES"
"1","(-3600,1950)","1","pure_quanta","I21";
;
LOCATION"PR3980"
$SEC"1"
CDS_SEC"1"
PACK_TYPE"0402LF"
MATERIAL"CHIP"
TOLERANCE"5%"
VALUE"0"
WATTAGE"1/16W"
ROOM"HSC BOM1"
CDS_LIB"pure_quanta"
PART_NUMBER"CS00002JB13";
"B"
$PN"2"2;
"A"
$PN"1"14;
%"UNIVERSAL_GND"
"1","(-2700,525)","0","pure_quanta_power","I23";
;
HDL_POWER"AGND_HSC"
CDS_LIB"pure_quanta_power";
"A"9;
%"Q_CAP"
"1","(-2700,825)","0","pure_quanta","I24";
;
LOCATION"PC2224"
$SEC"1"
CDS_SEC"1"
PACK_TYPE"0402"
VALUE"220PF"
ROOM"HSC BOM1"
VOLTAGE"50V"
MATERIAL"EMPTY"
TOLERANCE"10%"
CDS_LIB"pure_quanta"
PART_NUMBER"TMP_QCH12206KB14";
"B"
$PN"2"9;
"A"
$PN"1"21;
%"UNIVERSAL_GND"
"1","(-2725,1575)","0","pure_quanta_power","I25";
;
HDL_POWER"AGND_HSC"
CDS_LIB"pure_quanta_power";
"A"13;
%"Q_RES"
"1","(-1900,1650)","0","pure_quanta","I28";
;
LOCATION"PR3982"
$SEC"1"
CDS_SEC"1"
PACK_TYPE"0402LF"
MATERIAL"CHIP"
WATTAGE"1/16W"
VALUE"120K"
TOLERANCE"1%"
ROOM"HSC BOM1"
CDS_LIB"pure_quanta"
PART_NUMBER"CS41202FB05";
"B"
$PN"2"22;
"A"
$PN"1"13;
%"UNIVERSAL_POWER"
"1","(-3600,2200)","0","pure_quanta_power","I29";
;
HDL_POWER"HSC_VDD"
CDS_LIB"pure_quanta_power"
BOM_COST"MIO_VRD_SB";
"A"2;
%"UNIVERSAL_GND"
"1","(-3575,-1600)","0","pure_quanta_power","I3";
;
HDL_POWER"AGND_HSC"
CDS_LIB"pure_quanta_power";
"A"3;
%"Q_CAP"
"1","(-1950,825)","0","pure_quanta","I30";
;
LOCATION"PC2350"
$SEC"1"
CDS_SEC"1"
VALUE"1NF"
VOLTAGE"50V"
MATERIAL"EMPTY"
PACK_TYPE"0402"
ROOM"HSC BOM1"
CDS_LIB"pure_quanta"
TOLERANCE"10%"
PART_NUMBER"CH21006KB16";
"B"
$PN"2"9;
"A"
$PN"1"20;
%"Q_RES"
"2","(-1475,825)","0","pure_quanta","I31";
;
LOCATION"PR3986"
$SEC"1"
CDS_SEC"1"
VALUE"2K"
MATERIAL"CHIP"
TOLERANCE"0.1%"
WATTAGE"1/16W"
PACK_TYPE"0402LF"
ROOM"HSC BOM1"
CDS_LIB"pure_quanta"
PART_NUMBER"CS22002BB07";
"A"
$PN"1"11;
"B"
$PN"2"9;
%"Q_RES"
"1","(-1325,1475)","0","pure_quanta","I33";
;
LOCATION"PR3988"
$SEC"1"
CDS_SEC"1"
ROOM"HSC BOM1"
VALUE"0"
TOLERANCE"5%"
MATERIAL"CHIP"
PACK_TYPE"0402LF"
WATTAGE"1/16W"
CDS_LIB"pure_quanta"
PART_NUMBER"CS00002JB13";
"B"
$PN"2"19;
"A"
$PN"1"12;
%"Q_RES"
"2","(-950,825)","0","pure_quanta","I34";
;
LOCATION"PR3990"
$SEC"1"
CDS_SEC"1"
TOLERANCE"0.1%"
MATERIAL"CHIP"
VALUE"2K"
WATTAGE"1/16W"
PACK_TYPE"0402LF"
ROOM"HSC BOM1"
CDS_LIB"pure_quanta"
PART_NUMBER"CS22002BB07";
"A"
$PN"1"10;
"B"
$PN"2"9;
%"MP5991GLUZ"
"1","(25,1575)","0","pure_quanta","I35";
;
LOCATION"PU296"
SEC"1"
ROOM"HSC BOM1"
MATERIAL"IC"
PART_TYPE"SMLF"
VALUE"MP5991GLU-Z"
SEC_TYPE""
NEEDS_NO_SIZE"TRUE"
CDS_LMAN_SYM_OUTLINE"-325,775,325,-775"
CDS_LIB"pure_quanta"
PART_NUMBER"AL005991A00";
"NC1"
$PN"7"18;
"FLT_TYPE"
$PN"6"23;
"SCREF_OCWREF"
$PN"17"19;
"MODE"
$PN"8"22;
"VOUT10"
$PN"32"38;
"VOUT9"
$PN"31"38;
"VOUT8"
$PN"30"38;
"VOUT7"
$PN"29"38;
"VOUT6"
$PN"28"38;
"VOUT5"
$PN"27"38;
"VIN9"
$PN"33"36;
"VIN8"
$PN"16"36;
"VIN7"
$PN"15"36;
"VIN6"
$PN"14"36;
"D_OC"
$PN"3"24;
"VOUT4"
$PN"26"38;
"VOUT3"
$PN"25"38;
"VOUT2"
$PN"2"38;
"VOUT1"
$PN"1"38;
"VTEMP"
$PN"18"28;
"GOK"
$PN"5"27;
"SS"
$PN"19"29;
"GND"
$PN"20"9;
"VDD33"
$PN"21"14;
"IMON"
$PN"22"10;
"CS"
$PN"23"11;
"OCREF"
$PN"24"20;
"ON"
$PN"4"21;
"VIN5"
$PN"13"36;
"VIN4"
$PN"12"36;
"VIN3"
$PN"11"36;
"VIN2"
$PN"10"36;
"VIN1"
$PN"9"36;
%"UNIVERSAL_POWER"
"1","(-950,2450)","0","pure_quanta_power","I36";
;
HDL_POWER"P12V_PSU"
BOM_COST"MIO_VRD_SB"
CDS_LIB"pure_quanta_power";
"A"36;
%"UNIVERSAL_GND"
"1","(1000,-2150)","0","pure_quanta_power","I37";
;
HDL_POWER"AGND_HSC"
CDS_LIB"pure_quanta_power";
"A"4;
%"Q_CAP"
"1","(1000,-1925)","0","pure_quanta","I38";
;
LOCATION"PC2227"
$SEC"1"
CDS_SEC"1"
VALUE"0.068UF"
VOLTAGE"16V"
ROOM"HSC BOM1"
MATERIAL"X7R"
PACK_TYPE"0402"
CDS_LIB"pure_quanta"
TOLERANCE"10%"
PART_NUMBER"CH3683K1B09";
"B"
$PN"2"4;
"A"
$PN"1"42;
%"Q_RES"
"1","(1500,-1375)","0","pure_quanta","I39";
;
LOCATION"PR3995"
$SEC"1"
CDS_SEC"1"
ROOM"HSC BOM1"
PACK_TYPE"0402LF"
WATTAGE"1/16W"
MATERIAL"CHIP"
VALUE"0"
TOLERANCE"5%"
CDS_LIB"pure_quanta"
PART_NUMBER"CS00002JB13";
"B"
$PN"2"17;
"A"
$PN"1"46;
%"Q_CAP"
"1","(-3575,-1300)","0","pure_quanta","I4";
;
LOCATION"PC2223"
$SEC"1"
CDS_SEC"1"
VALUE"1UF"
VOLTAGE"25V"
MATERIAL"X6S"
ROOM"HSC BOM1"
PACK_TYPE"C0402"
TOLERANCE"10%"
CDS_LIB"pure_quanta"
PART_NUMBER"CH5104KEB02";
"B"
$PN"2"3;
"A"
$PN"1"34;
%"Q_RES"
"1","(1500,-1200)","0","pure_quanta","I40";
;
LOCATION"PR3994"
$SEC"1"
CDS_SEC"1"
MATERIAL"CHIP"
PACK_TYPE"0402LF"
WATTAGE"1/16W"
TOLERANCE"5%"
ROOM"HSC BOM1"
VALUE"0"
CDS_LIB"pure_quanta"
PART_NUMBER"CS00002JB13";
"B"
$PN"2"40;
"A"
$PN"1"41;
%"UNIVERSAL_POWER"
"1","(1125,-325)","0","pure_quanta_power","I41";
;
HDL_POWER"P12V_AUX"
BOM_COST"MIO_VRD_SB"
CDS_LIB"pure_quanta_power";
"A"37;
%"Q_CAP"
"1","(1000,850)","0","pure_quanta","I47";
;
LOCATION"PC2226"
$SEC"1"
CDS_SEC"1"
ROOM"HSC BOM1"
VALUE"0.068UF"
VOLTAGE"16V"
MATERIAL"X7R"
PACK_TYPE"0402"
CDS_LIB"pure_quanta"
TOLERANCE"10%"
PART_NUMBER"CH3683K1B09";
"B"
$PN"2"5;
"A"
$PN"1"29;
%"UNIVERSAL_GND"
"1","(1000,625)","0","pure_quanta_power","I48";
;
HDL_POWER"AGND_HSC"
CDS_LIB"pure_quanta_power";
"A"5;
%"Q_RES"
"1","(1500,1400)","0","pure_quanta","I49";
;
LOCATION"PR3993"
$SEC"1"
CDS_SEC"1"
ROOM"HSC BOM1"
VALUE"0"
WATTAGE"1/16W"
TOLERANCE"5%"
MATERIAL"CHIP"
PACK_TYPE"0402LF"
CDS_LIB"pure_quanta"
PART_NUMBER"CS00002JB13";
"B"
$PN"2"26;
"A"
$PN"1"23;
%"Q_RES"
"1","(1500,1575)","0","pure_quanta","I50";
;
LOCATION"PR3992"
$SEC"1"
CDS_SEC"1"
WATTAGE"1/16W"
PACK_TYPE"0402LF"
ROOM"HSC BOM1"
VALUE"0"
TOLERANCE"5%"
MATERIAL"CHIP"
CDS_LIB"pure_quanta"
PART_NUMBER"CS00002JB13";
"B"
$PN"2"25;
"A"
$PN"1"24;
%"UNIVERSAL_POWER"
"1","(1125,2450)","0","pure_quanta_power","I51";
;
HDL_POWER"P12V_AUX"
BOM_COST"MIO_VRD_SB"
CDS_LIB"pure_quanta_power";
"A"38;
%"Q_RES"
"1","(-3575,-825)","1","pure_quanta","I6";
;
LOCATION"PR3981"
$SEC"1"
CDS_SEC"1"
PACK_TYPE"0402LF"
VALUE"0"
TOLERANCE"5%"
WATTAGE"1/16W"
MATERIAL"CHIP"
ROOM"HSC BOM1"
CDS_LIB"pure_quanta"
PART_NUMBER"CS00002JB13";
"B"
$PN"2"6;
"A"
$PN"1"34;
%"UNIVERSAL_POWER"
"1","(-3575,-575)","0","pure_quanta_power","I7";
;
HDL_POWER"HSC_VDD"
BOM_COST"MIO_VRD_SB"
CDS_LIB"pure_quanta_power";
"A"6;
%"UNIVERSAL_GND"
"1","(-2700,-1225)","0","pure_quanta_power","I8";
;
HDL_POWER"AGND_HSC"
CDS_LIB"pure_quanta_power";
"A"39;
END.
